Created on Valor NPI 9.6 Update 2 - Netlist Compare Summary.
DATE :  21 Jun 2017
TIME :  10:32:56


     MISMATCH SUMMARY REPORT
     -----------------------

Job  : 16316-1                 Job  : 16316-1
Step : q                       Step : q
Type : CAD                     Type : CURCAD

-----------------------------------------------

 Mismatch Type: shorted

   GND                   -   NET00002            
   AGND_P0V9             -    "                  
   AGND_P3V3             -    "                  
   AGND_P1V5_E           -    "                  
   AGND_P0V975           -    "                  
   AGND_CURRENT_MON      -    "                  

 Total : 1
-----------------------------------------------

 Mismatch Type: broken


 Total : 0
-----------------------------------------------

 Mismatch Type: missing


 Total : 0
-----------------------------------------------

 Mismatch Type: extra


 Total : 0
-----------------------------------------------
